# S9S_MB_2U (Grand Teton) — schematic netlist excerpt (pin names and nets, part order shuffled) for the footprints in the layout excerpt that follows; sources: Cadence DE-HDL packaged netlist, KiCad conversion of 03242023_DA0F0TMBIJ0_F0T_Motherboard_J_brd_V01_OCP.brd

J100  SCONN20_513860200CV01  SCONN20_51386-0200C-V01 IO  pkg HEADER2X10SBHXB  page 228
  \1\  = SMB_SML0_ME_SCL
  \2\  = GND
  \3\  = SMB_SML0_ME_SDA
  \4\  = IRQ_SML0_ALERT_R1_N
  \5\  = SMB_PMBUS_SML1_ME_SCL
  \6\  = GND
  \7\  = SMB_PMBUS_SML1_ME_SDA
  \8\  = IRQ_SML1_PMBUS_ALERT_R_N
  \9\  = RST_RSMRST_NM_HDR_N
  \10\  = GND
  \11\  = SMB_HOST_ME_SCL
  \12\  = GND
  \13\  = SMB_HOST_ME_SDA
  \14\  = NC
  \15\  = GND
  \16\  = PECI_BMC_ME
  \17\  = GND
  \18\  = PWRGD_PS_PWROK_ME_CONN
  \19\  = FM_BIOS_POST_CMPLT_HDR_N
  \20\  = NC

(kicad_pcb
	(version 20260206)
	(generator "pcbnew")
	(generator_version "10.0")
	(general
		(thickness 1.6)
		(legacy_teardrops no)
	)
	(paper "A4")
	(title_block
		(title "03242023_DA0F0TMBIJ0_F0T_Motherboard_J_brd_V01_OCP.brd")
		(comment 1 "Grand Teton / footprint 3489 of 6105 (J100), pads 1-22 of 22")
	)
	(layers
		(0 "F.Cu" signal "TOP")
		(4 "In1.Cu" signal "GND")
		(6 "In2.Cu" signal "IN1")
		(8 "In3.Cu" signal "GND1")
		(10 "In4.Cu" signal "IN2")
		(12 "In5.Cu" signal "GND2")
		(14 "In6.Cu" signal "IN3")
		(16 "In7.Cu" signal "GND3")
		(18 "In8.Cu" signal "VCC")
		(20 "In9.Cu" signal "VCC1")
		(22 "In10.Cu" signal "GND4")
		(24 "In11.Cu" signal "IN4")
		(26 "In12.Cu" signal "GND5")
		(28 "In13.Cu" signal "IN5")
		(30 "In14.Cu" signal "GND6")
		(32 "In15.Cu" signal "IN6")
		(34 "In16.Cu" signal "GND7")
		(2 "B.Cu" signal "BOTTOM")
		(9 "F.Adhes" user "F.Adhesive")
		(11 "B.Adhes" user "B.Adhesive")
		(13 "F.Paste" user "Package Geometry/Pastemask Top")
		(15 "B.Paste" user "Package Geometry/Pastemask Bottom")
		(5 "F.SilkS" user "Ref Des/Silkscreen Top")
		(7 "B.SilkS" user "Ref Des/Silkscreen Bottom")
		(1 "F.Mask" user "Board Geometry/Soldermask Top")
		(3 "B.Mask" user "Board Geometry/Soldermask Bottom")
		(17 "Dwgs.User" user "User.Drawings")
		(19 "Cmts.User" user "User.Comments")
		(21 "Eco1.User" user "User.Eco1")
		(23 "Eco2.User" user "User.Eco2")
		(25 "Edge.Cuts" user "Board Geometry/Outline")
		(27 "Margin" user)
		(31 "F.CrtYd" user "Package Geometry/Place Bound Top")
		(29 "B.CrtYd" user "Package Geometry/Place Bound Bottom")
		(35 "F.Fab" user "Ref Des/Assembly Top")
		(33 "B.Fab" user "Ref Des/Assembly Bottom")
	)
	(footprint ""
		(layer "F.Cu")
		(at 17.899888 -51.999896)
		(property "Reference" "J100"
			(at -2.413 -12.080748 0)
			(unlocked yes)
			(layer "F.SilkS")
			(effects
				(font
					(size 0.7874 0.5842)
					(thickness 0.1524)
				)
			)
		)
		(property "Value" ""
			(at 0 0 0)
			(layer "F.Fab")
			(effects
				(font
					(size 1.27 1.27)
				)
			)
		)
		(duplicate_pad_numbers_are_jumpers no)
		(pad "" np_thru_hole circle
			(at 0 -7.999984 270)
			(size 1.016 1.016)
			(drill 1.016)
			(layers "*.Cu" "*.Mask")
			(clearance 0.381)
			(thermal_gap 0.381)
		)
		(pad "" np_thru_hole circle
			(at 0 7.999984 270)
			(size 1.016 1.016)
			(drill 1.016)
			(layers "*.Cu" "*.Mask")
			(clearance 0.381)
			(thermal_gap 0.381)
		)
		(pad "1" smd rect
			(at -2.124964 -8.999982 270)
			(size 0.9144 2.7686)
			(layers "F.Cu" "F.Mask" "F.Paste")
			(net "SMB_SML0_ME_SCL")
		)
		(pad "2" smd rect
			(at 2.124964 -8.999982 270)
			(size 0.9144 2.7686)
			(layers "F.Cu" "F.Mask" "F.Paste")
			(net "GND")
		)
		(pad "3" smd rect
			(at -2.124964 -6.999986 270)
			(size 0.9144 2.7686)
			(layers "F.Cu" "F.Mask" "F.Paste")
			(net "SMB_SML0_ME_SDA")
		)
		(pad "4" smd rect
			(at 2.124964 -6.999986 270)
			(size 0.9144 2.7686)
			(layers "F.Cu" "F.Mask" "F.Paste")
			(net "IRQ_SML0_ALERT_R1_N")
		)
		(pad "5" smd rect
			(at -2.124964 -4.99999 270)
			(size 0.9144 2.7686)
			(layers "F.Cu" "F.Mask" "F.Paste")
			(net "SMB_PMBUS_SML1_ME_SCL")
		)
		(pad "6" smd rect
			(at 2.124964 -4.99999 270)
			(size 0.9144 2.7686)
			(layers "F.Cu" "F.Mask" "F.Paste")
			(net "GND")
		)
		(pad "7" smd rect
			(at -2.124964 -2.999994 270)
			(size 0.9144 2.7686)
			(layers "F.Cu" "F.Mask" "F.Paste")
			(net "SMB_PMBUS_SML1_ME_SDA")
		)
		(pad "8" smd rect
			(at 2.124964 -2.999994 270)
			(size 0.9144 2.7686)
			(layers "F.Cu" "F.Mask" "F.Paste")
			(net "IRQ_SML1_PMBUS_ALERT_R_N")
		)
		(pad "9" smd rect
			(at -2.124964 -0.999998 270)
			(size 0.9144 2.7686)
			(layers "F.Cu" "F.Mask" "F.Paste")
			(net "RST_RSMRST_NM_HDR_N")
		)
		(pad "10" smd rect
			(at 2.124964 -0.999998 270)
			(size 0.9144 2.7686)
			(layers "F.Cu" "F.Mask" "F.Paste")
			(net "GND")
		)
		(pad "11" smd rect
			(at -2.124964 0.999998 270)
			(size 0.9144 2.7686)
			(layers "F.Cu" "F.Mask" "F.Paste")
			(net "SMB_HOST_ME_SCL")
		)
		(pad "12" smd rect
			(at 2.124964 0.999998 270)
			(size 0.9144 2.7686)
			(layers "F.Cu" "F.Mask" "F.Paste")
			(net "GND")
		)
		(pad "13" smd rect
			(at -2.124964 2.999994 270)
			(size 0.9144 2.7686)
			(layers "F.Cu" "F.Mask" "F.Paste")
			(net "SMB_HOST_ME_SDA")
		)
		(pad "14" smd rect
			(at 2.124964 2.999994 270)
			(size 0.9144 2.7686)
			(layers "F.Cu" "F.Mask" "F.Paste")
			(net "Net_8591")
		)
		(pad "15" smd rect
			(at -2.124964 4.99999 270)
			(size 0.9144 2.7686)
			(layers "F.Cu" "F.Mask" "F.Paste")
			(net "GND")
		)
		(pad "16" smd rect
			(at 2.124964 4.99999 270)
			(size 0.9144 2.7686)
			(layers "F.Cu" "F.Mask" "F.Paste")
			(net "PECI_BMC_ME")
		)
		(pad "17" smd rect
			(at -2.124964 6.999986 270)
			(size 0.9144 2.7686)
			(layers "F.Cu" "F.Mask" "F.Paste")
			(net "GND")
		)
		(pad "18" smd rect
			(at 2.124964 6.999986 270)
			(size 0.9144 2.7686)
			(layers "F.Cu" "F.Mask" "F.Paste")
			(net "PWRGD_PS_PWROK_ME_CONN")
		)
		(pad "19" smd rect
			(at -2.124964 8.999982 270)
			(size 0.9144 2.7686)
			(layers "F.Cu" "F.Mask" "F.Paste")
			(net "FM_BIOS_POST_CMPLT_HDR_N")
		)
		(pad "20" smd rect
			(at 2.124964 8.999982 270)
			(size 0.9144 2.7686)
			(layers "F.Cu" "F.Mask" "F.Paste")
			(net "Net_8590")
		)
	)
)
